# TIMECARD (Time Appliance Project (Time Card)) — schematic netlist excerpt (pin names and nets, part order shuffled) for the footprints in the layout excerpt that follows; sources: Cadence DE-HDL packaged netlist, KiCad conversion of R4006-B0001-02_R01.brd

TP6  TP_PIONT  pkg TP010CT020B030_PTH  page 24 : \1\ = UNNAMED_524_FT4232HLREELQFP64_1

J2  CONN_JACK_1P_GH4_S_TH  2081680-1  pkg P_F_JACK_1P_GH4_RA_P200  page 23
  \1\  = SMA4_SIG_IO_CONN
  GH1  = SG
  GH2  = SG
  GH3  = SG
  GH4  = SG

(kicad_pcb
	(version 20260206)
	(generator "pcbnew")
	(generator_version "10.0")
	(general
		(thickness 1.6)
		(legacy_teardrops no)
	)
	(paper "A4")
	(title_block
		(title "timecard-production-celestica-r4006 — R4006-B0001-02_R01.brd")
		(comment 1 "Time Appliance Project (Time Card) / footprints 654-655 of 1113")
	)
	(layers
		(0 "F.Cu" signal "TOP")
		(4 "In1.Cu" signal "L02_GND1")
		(6 "In2.Cu" signal "L03_SIG1")
		(8 "In3.Cu" signal "L04_GND2")
		(10 "In4.Cu" signal "L05_VCC1")
		(12 "In5.Cu" signal "L06_VCC2")
		(14 "In6.Cu" signal "L07_GND3")
		(16 "In7.Cu" signal "L08_SIG2")
		(18 "In8.Cu" signal "L09_GND4")
		(2 "B.Cu" signal "BOTTOM")
		(9 "F.Adhes" user "F.Adhesive")
		(11 "B.Adhes" user "B.Adhesive")
		(13 "F.Paste" user "Package Geometry/Pastemask Top")
		(15 "B.Paste" user "Package Geometry/Pastemask Bottom")
		(5 "F.SilkS" user "Ref Des/Silkscreen Top")
		(7 "B.SilkS" user "Ref Des/Silkscreen Bottom")
		(1 "F.Mask" user "Board Geometry/Soldermask Top")
		(3 "B.Mask" user "Board Geometry/Soldermask Bottom")
		(17 "Dwgs.User" user "User.Drawings")
		(19 "Cmts.User" user "User.Comments")
		(21 "Eco1.User" user "User.Eco1")
		(23 "Eco2.User" user "User.Eco2")
		(25 "Edge.Cuts" user "Board Geometry/Outline")
		(27 "Margin" user)
		(31 "F.CrtYd" user "Package Geometry/Place Bound Top")
		(29 "B.CrtYd" user "Package Geometry/Place Bound Bottom")
		(35 "F.Fab" user "Ref Des/Assembly Top")
		(33 "B.Fab" user "Ref Des/Assembly Bottom")
	)
	(footprint ""
		(layer "F.Cu")
		(at 4.073906 -18.10004)
		(property "Reference" "J2"
			(at 4.943094 3.40741 0)
			(unlocked yes)
			(layer "F.SilkS")
			(effects
				(font
					(size 0.7874 0.5842)
					(thickness 0.1524)
				)
			)
		)
		(property "Value" ""
			(at 0 0 0)
			(layer "F.Fab")
			(effects
				(font
					(size 1.27 1.27)
				)
			)
		)
		(property "Device Type" "CONN_JACK_1P_GH4_S_TH-G200-130A"
			(at -5.098288 5.899912 0)
			(unlocked yes)
			(layer "F.Fab")
			(hide yes)
			(effects
				(font
					(size 0.7874 0.5842)
					(thickness 0.1524)
				)
			)
		)
		(property "User Part Number" "PARTNUM*"
			(at -5.098288 7.093712 0)
			(unlocked yes)
			(layer "Cmts.User")
			(hide yes)
			(effects
				(font
					(size 0.7874 0.5842)
					(thickness 0.1524)
				)
			)
		)
		(duplicate_pad_numbers_are_jumpers no)
		(fp_line
			(start -13.953998 -3.937)
			(end 3.937 -3.937)
			(stroke
				(width 0.1)
				(type default)
			)
			(layer "F.SilkS")
		)
		(fp_line
			(start -13.953998 3.937)
			(end -13.953998 -3.937)
			(stroke
				(width 0.1)
				(type default)
			)
			(layer "F.SilkS")
		)
		(fp_line
			(start 3.937 -3.937)
			(end 3.937 3.937)
			(stroke
				(width 0.1)
				(type default)
			)
			(layer "F.SilkS")
		)
		(fp_line
			(start 3.937 3.937)
			(end -13.953998 3.937)
			(stroke
				(width 0.1)
				(type default)
			)
			(layer "F.SilkS")
		)
		(fp_rect
			(start -8.763 8.763)
			(end 8.763 -8.763)
			(stroke
				(width 0)
				(type default)
			)
			(fill no)
			(layer "B.CrtYd")
		)
		(fp_rect
			(start -14.207998 4.191)
			(end 4.191 -4.191)
			(stroke
				(width 0)
				(type default)
			)
			(fill no)
			(layer "F.CrtYd")
		)
		(fp_line
			(start -13.699998 -3.599942)
			(end 3.599942 -3.599942)
			(stroke
				(width 0.1)
				(type default)
			)
			(layer "F.Fab")
		)
		(fp_line
			(start -13.699998 3.599942)
			(end -13.699998 -3.599942)
			(stroke
				(width 0.1)
				(type default)
			)
			(layer "F.Fab")
		)
		(fp_line
			(start 3.599942 -3.599942)
			(end 3.599942 3.599942)
			(stroke
				(width 0.1)
				(type default)
			)
			(layer "F.Fab")
		)
		(fp_line
			(start 3.599942 3.599942)
			(end -13.699998 3.599942)
			(stroke
				(width 0.1)
				(type default)
			)
			(layer "F.Fab")
		)
		(fp_text user "GH3"
			(at -1.660906 4.55041 0)
			(unlocked yes)
			(layer "F.SilkS")
			(effects
				(font
					(size 0.7874 0.5842)
					(thickness 0.1524)
				)
			)
		)
		(fp_text user "GH1"
			(at -0.263906 -4.34721 0)
			(unlocked yes)
			(layer "F.SilkS")
			(effects
				(font
					(size 0.635 0.4064)
					(thickness 0.1524)
				)
			)
		)
		(fp_text user "GH2"
			(at 2.276094 -4.34721 0)
			(unlocked yes)
			(layer "F.SilkS")
			(effects
				(font
					(size 0.635 0.4064)
					(thickness 0.1524)
				)
			)
		)
		(fp_text user "GH4"
			(at 2.784094 4.67741 0)
			(unlocked yes)
			(layer "F.SilkS")
			(effects
				(font
					(size 0.7874 0.5842)
					(thickness 0.1524)
				)
			)
		)
		(fp_text user "1"
			(at 4.191 -0.35433 0)
			(unlocked yes)
			(layer "F.SilkS")
			(effects
				(font
					(size 0.7874 0.5842)
					(thickness 0.1524)
				)
				(justify left)
			)
		)
		(fp_text user "GH3"
			(at -2.803906 4.187698 0)
			(unlocked yes)
			(layer "F.Fab")
			(effects
				(font
					(size 0.7874 0.5842)
					(thickness 0.1524)
				)
			)
		)
		(fp_text user "GH1"
			(at -2.295906 -4.08559 0)
			(unlocked yes)
			(layer "F.Fab")
			(effects
				(font
					(size 0.7874 0.5842)
					(thickness 0.1524)
				)
			)
		)
		(fp_text user "GH2"
			(at 2.530094 -4.08559 0)
			(unlocked yes)
			(layer "F.Fab")
			(effects
				(font
					(size 0.7874 0.5842)
					(thickness 0.1524)
				)
			)
		)
		(fp_text user "GH4"
			(at 2.54 4.64947 0)
			(unlocked yes)
			(layer "F.Fab")
			(effects
				(font
					(size 0.7874 0.5842)
					(thickness 0.1524)
				)
			)
		)
		(fp_text user "1"
			(at 4.191 -0.35433 0)
			(unlocked yes)
			(layer "F.Fab")
			(effects
				(font
					(size 0.7874 0.5842)
					(thickness 0.1524)
				)
				(justify left)
			)
		)
		(pad "1" thru_hole circle
			(at 0 0)
			(size 2.1844 2.1844)
			(drill 1.4986)
			(layers "*.Cu" "*.Mask")
			(remove_unused_layers no)
			(net "SMA4_SIG_IO_CONN")
			(padstack
				(mode front_inner_back)
				(layer "Inner"
					(shape circle)
					(size 2.1844 2.1844)
					(clearance -0.0508)
				)
				(layer "B.Cu"
					(shape circle)
					(size 2.1844 2.1844)
				)
			)
		)
		(pad "GH1" thru_hole circle
			(at -2.54 -2.54)
			(size 2.286 2.286)
			(drill 1.6002)
			(layers "*.Cu" "*.Mask")
			(remove_unused_layers no)
			(net "SG")
			(padstack
				(mode front_inner_back)
				(layer "Inner"
					(shape circle)
					(size 2.286 2.286)
					(clearance -0.0508)
				)
				(layer "B.Cu"
					(shape circle)
					(size 2.286 2.286)
				)
			)
		)
		(pad "GH2" thru_hole circle
			(at 2.54 -2.54)
			(size 2.286 2.286)
			(drill 1.6002)
			(layers "*.Cu" "*.Mask")
			(remove_unused_layers no)
			(net "SG")
			(padstack
				(mode front_inner_back)
				(layer "Inner"
					(shape circle)
					(size 2.286 2.286)
					(clearance -0.0508)
				)
				(layer "B.Cu"
					(shape circle)
					(size 2.286 2.286)
				)
			)
		)
		(pad "GH3" thru_hole circle
			(at -2.54 2.54)
			(size 2.286 2.286)
			(drill 1.6002)
			(layers "*.Cu" "*.Mask")
			(remove_unused_layers no)
			(net "SG")
			(padstack
				(mode front_inner_back)
				(layer "Inner"
					(shape circle)
					(size 2.286 2.286)
					(clearance -0.0508)
				)
				(layer "B.Cu"
					(shape circle)
					(size 2.286 2.286)
				)
			)
		)
		(pad "GH4" thru_hole circle
			(at 2.54 2.54)
			(size 2.286 2.286)
			(drill 1.6002)
			(layers "*.Cu" "*.Mask")
			(remove_unused_layers no)
			(net "SG")
			(padstack
				(mode front_inner_back)
				(layer "Inner"
					(shape circle)
					(size 2.286 2.286)
					(clearance -0.0508)
				)
				(layer "B.Cu"
					(shape circle)
					(size 2.286 2.286)
				)
			)
		)
	)
	(footprint ""
		(layer "F.Cu")
		(at 20.193 -78.359)
		(property "Reference" "TP6"
			(at 0.29337 3.2385 90)
			(unlocked yes)
			(layer "F.SilkS")
			(effects
				(font
					(size 0.7874 0.5842)
					(thickness 0.1524)
				)
				(justify left)
			)
		)
		(property "Value" ""
			(at 0 0 0)
			(layer "F.Fab")
			(effects
				(font
					(size 1.27 1.27)
				)
			)
		)
		(property "Device Type" "TP_PIONT-TP010CT020B030_PTH-TPA"
			(at -1.341882 0.996696 0)
			(unlocked yes)
			(layer "F.Fab")
			(hide yes)
			(effects
				(font
					(size 0.7874 0.5842)
					(thickness 0.1524)
				)
				(justify left)
			)
		)
		(duplicate_pad_numbers_are_jumpers no)
		(fp_poly
			(pts
				(arc
					(start 0.889 0)
					(mid -0.889 0)
					(end 0.889 0)
				)
			)
			(stroke
				(width 0)
				(type default)
			)
			(fill no)
			(layer "B.CrtYd")
		)
		(fp_poly
			(pts
				(arc
					(start 0.889 0)
					(mid -0.889 0)
					(end 0.889 0)
				)
			)
			(stroke
				(width 0)
				(type default)
			)
			(fill no)
			(layer "F.CrtYd")
		)
		(pad "1" thru_hole circle
			(at 0 0)
			(size 0.508 0.508)
			(drill 0.254)
			(layers "*.Cu" "*.Mask")
			(remove_unused_layers no)
			(net "UNNAMED_524_FT4232HLREELQFP64_1")
			(clearance 0.1016)
			(padstack
				(mode front_inner_back)
				(layer "Inner"
					(shape circle)
					(size 0.508 0.508)
					(clearance 0.1016)
				)
				(layer "B.Cu"
					(shape circle)
					(size 0.762 0.762)
					(clearance -0.0254)
				)
			)
		)
	)
)
